
Section 2 - Conflicts on Net Synonyms
--------------------------------------

DRAWING = @BASEBOARD_FAB2_LIB.BASEBOARD_FAB2(SCH_1)
NET_NAME = PVCCIOMCP_CPU1
   OPF: VOLTAGE = +0.95; NET = PVCCIOMCP_CPU1
 * SCH: VOLTAGE = +0.95V
NET_NAME = P3V3_STBY
   OPF: VOLTAGE = 3.3; NET = P3V3_STBY
   OPF: VOLTAGE = +3.3V; NET = P3V3_STBY
   OPF: VOLTAGE = +3.3V; NET = P3V3_STBY
   OPF: VOLTAGE = +3.3V; NET = P3V3_STBY
   OPF: VOLTAGE = +3.3V; NET = P3V3_STBY
   OPF: VOLTAGE = +3.3V; NET = P3V3_STBY
   OPF: VOLTAGE = +3.3V; NET = P3V3_STBY
   OPF: VOLTAGE = +3.3V; NET = P3V3_STBY
   OPF: VOLTAGE = +3.3V; NET = P3V3_STBY
   OPF: VOLTAGE = +3.3V; NET = P3V3_STBY
   OPF: VOLTAGE = +3.3V; NET = P3V3_STBY
 * SCH: VOLTAGE = 3.3V
NET_NAME = P12V
   OPF: VOLTAGE = 12.0V; NET = P12V
   OPF: VOLTAGE = 12.0V; NET = P12V
   OPF: VOLTAGE = +12.0V; NET = P12V
 * SCH: VOLTAGE = +12.
NET_NAME = P3V3
   OPF: VOLTAGE = +3.3; NET = P3V3
   OPF: VOLTAGE = +3.3; NET = P3V3
   OPF: VOLTAGE = +3.3; NET = P3V3
   OPF: VOLTAGE = +3.3V; NET = P3V3
   OPF: VOLTAGE = +3.3V; NET = P3V3
   OPF: VOLTAGE = +3.3V; NET = P3V3
 * SCH: VOLTAGE = 3.3V
NET_NAME = P5V
   OPF: VOLTAGE = +5.0V; NET = P5V
   OPF: VOLTAGE = +5.0V; NET = P5V
   OPF: VOLTAGE = +5.0V; NET = P5V
 * SCH: VOLTAGE = 5.0V
NET_NAME = P5V_STBY
   OPF: VOLTAGE = +5.0V; NET = P5V_STBY
   OPF: VOLTAGE = +5.0V; NET = P5V_STBY
   OPF: VOLTAGE = +5.0V; NET = P5V_STBY
   OPF: VOLTAGE = +5; NET = P5V_STBY
 * SCH: VOLTAGE = 5.0V
NET_NAME = GND
   OPF: VOLTAGE = 0; NET = GND
   OPF: VOLTAGE = 0; NET = GND
   OPF: VOLTAGE = 0; NET = GND
   OPF: VOLTAGE = 0; NET = GND
   OPF: VOLTAGE = 0; NET = GND
   OPF: VOLTAGE = 0; NET = GND
   OPF: VOLTAGE = 0; NET = GND
   OPF: VOLTAGE = 0; NET = GND
   OPF: VOLTAGE = 0; NET = GND
   OPF: VOLTAGE = 0; NET = GND
   OPF: VOLTAGE = 0; NET = GND
   OPF: VOLTAGE = 0; NET = GND
   OPF: VOLTAGE = 0; NET = GND
   OPF: VOLTAGE = 0; NET = GND
   OPF: VOLTAGE = 0; NET = GND
   OPF: VOLTAGE = 0; NET = GND
   OPF: VOLTAGE = 0; NET = GND
   OPF: VOLTAGE = 0; NET = GND
   OPF: VOLTAGE = 0; NET = GND
   OPF: VOLTAGE = 0; NET = GND
   OPF: VOLTAGE = 0; NET = GND
   OPF: VOLTAGE = 0; NET = GND
   OPF: VOLTAGE = 0; NET = GND
   OPF: VOLTAGE = 0; NET = GND
   OPF: VOLTAGE = 0; NET = GND
   OPF: VOLTAGE = 0; NET = GND
   OPF: VOLTAGE = 0; NET = GND
   OPF: VOLTAGE = 0; NET = GND
   OPF: VOLTAGE = 0; NET = GND
   OPF: VOLTAGE = 0; NET = GND
   OPF: VOLTAGE = 0; NET = GND
   OPF: VOLTAGE = 0; NET = GND
   OPF: VOLTAGE = 0; NET = GND
   OPF: VOLTAGE = 0; NET = GND
   OPF: VOLTAGE = 0; NET = GND
   OPF: VOLTAGE = 0; NET = GND
   OPF: VOLTAGE = 0; NET = GND
   OPF: VOLTAGE = 0; NET = GND
   OPF: VOLTAGE = 0; NET = GND
   OPF: VOLTAGE = 0; NET = GND
   OPF: VOLTAGE = 0; NET = GND
   OPF: VOLTAGE = 0; NET = GND
   OPF: VOLTAGE = 0; NET = GND
   OPF: VOLTAGE = 0; NET = GND
   OPF: VOLTAGE = 0; NET = GND
   OPF: VOLTAGE = 0; NET = GND
   OPF: VOLTAGE = 0; NET = GND
   OPF: VOLTAGE = 0; NET = GND
   OPF: VOLTAGE = 0; NET = GND
   OPF: VOLTAGE = 0; NET = GND
   OPF: VOLTAGE = 0; NET = GND
   OPF: VOLTAGE = 0; NET = GND
   OPF: VOLTAGE = 0; NET = GND
   OPF: VOLTAGE = 0; NET = GND
   OPF: VOLTAGE = 0; NET = GND
   OPF: VOLTAGE = 0; NET = GND
   OPF: VOLTAGE = 0; NET = GND
   OPF: VOLTAGE = 0; NET = GND
   OPF: VOLTAGE = 0; NET = GND
   OPF: VOLTAGE = 0; NET = GND
   OPF: VOLTAGE = 0; NET = GND
   OPF: VOLTAGE = 0; NET = GND
   OPF: VOLTAGE = 0; NET = GND
   OPF: VOLTAGE = 0; NET = GND
   OPF: VOLTAGE = 0; NET = GND
   OPF: VOLTAGE = 0; NET = GND
   OPF: VOLTAGE = 0; NET = GND
   OPF: VOLTAGE = 0; NET = GND
   OPF: VOLTAGE = 0; NET = GND
   OPF: VOLTAGE = 0; NET = GND
   OPF: VOLTAGE = 0; NET = GND
   OPF: VOLTAGE = 0; NET = GND
   OPF: VOLTAGE = 0; NET = GND
   OPF: VOLTAGE = 0; NET = GND
   OPF: VOLTAGE = 0; NET = GND
   OPF: VOLTAGE = 0; NET = GND
   OPF: VOLTAGE = 0; NET = GND
   OPF: VOLTAGE = 0; NET = GND
   OPF: VOLTAGE = 0; NET = GND
   OPF: VOLTAGE = 0; NET = GND
   OPF: VOLTAGE = 0; NET = GND
   OPF: VOLTAGE = 0; NET = GND
   OPF: VOLTAGE = 0; NET = GND
   OPF: VOLTAGE = 0; NET = GND
   OPF: VOLTAGE = 0; NET = GND
   OPF: VOLTAGE = 0; NET = GND
   OPF: VOLTAGE = 0; NET = GND
   OPF: VOLTAGE = 0; NET = GND
   OPF: VOLTAGE = 0; NET = GND
   OPF: VOLTAGE = 0; NET = GND
   OPF: VOLTAGE = 0; NET = GND
 * SCH: VOLTAGE = 0.0V

Logical and Physical Net Conflicts 
----------------------------------

DRAWING = @BASEBOARD_FAB2_LIB.BASEBOARD_FAB2(SCH_1)
NET_NAME = FM_PCH_BMC_THERMTRIP_EXI_STRAP_N
   PNN = FM_PCH_BMC_THERMTRIP_EXI_STRAP_
NET_NAME = TP_JUMPER_BLOCK_ 1_7
   PNN = TP_JUMPER_BLOCK_1_7
NET_NAME = FM_FAST_PROCHOT_THROTTLE_DLY_BUF_N
   PNN = FM_FAST_PROCHOT_THROTTLE_DLY_BU
NET_NAME = PU_VR_PVCCIN_CPU0_FLT1_SMBALT_N_IMON
   PNN = PU_VR_PVCCIN_CPU0_FLT1_SMBALT_N
NET_NAME = PU_VR_PVCCIN_CPU1_FLT1_SMBALT_N_IMON
   PNN = PU_VR_PVCCIN_CPU1_FLT1_SMBALT_N
